# S9S_MB_2U (Grand Teton) — schematic netlist excerpt (pin names and nets, part order shuffled) for the footprints in the layout excerpt that follows; sources: Cadence DE-HDL packaged netlist, KiCad conversion of 03242023_DA0F0TMBIJ0_F0T_Motherboard_J_brd_V01_OCP.brd

R346  Q_RES  0 5% CHIP  pkg 0402LF  page 225 : A = H_CPU_ERR2_LVC1_R_N ; B = H_CPU_ERR2_LVC1_N
D65  Q_LED  IC  pkg SMLF  page 256 : A = LED_RST_PLD_CPU0_DRAM_AB_N ; C = LED_RST_PLD_CPU0_DRAM_AB_N_D

(kicad_pcb
	(version 20260206)
	(generator "pcbnew")
	(generator_version "10.0")
	(general
		(thickness 1.6)
		(legacy_teardrops no)
	)
	(paper "A4")
	(title_block
		(title "03242023_DA0F0TMBIJ0_F0T_Motherboard_J_brd_V01_OCP.brd")
		(comment 1 "Grand Teton / footprints 742-743 of 6105")
	)
	(layers
		(0 "F.Cu" signal "TOP")
		(4 "In1.Cu" signal "GND")
		(6 "In2.Cu" signal "IN1")
		(8 "In3.Cu" signal "GND1")
		(10 "In4.Cu" signal "IN2")
		(12 "In5.Cu" signal "GND2")
		(14 "In6.Cu" signal "IN3")
		(16 "In7.Cu" signal "GND3")
		(18 "In8.Cu" signal "VCC")
		(20 "In9.Cu" signal "VCC1")
		(22 "In10.Cu" signal "GND4")
		(24 "In11.Cu" signal "IN4")
		(26 "In12.Cu" signal "GND5")
		(28 "In13.Cu" signal "IN5")
		(30 "In14.Cu" signal "GND6")
		(32 "In15.Cu" signal "IN6")
		(34 "In16.Cu" signal "GND7")
		(2 "B.Cu" signal "BOTTOM")
		(9 "F.Adhes" user "F.Adhesive")
		(11 "B.Adhes" user "B.Adhesive")
		(13 "F.Paste" user "Package Geometry/Pastemask Top")
		(15 "B.Paste" user "Package Geometry/Pastemask Bottom")
		(5 "F.SilkS" user "Ref Des/Silkscreen Top")
		(7 "B.SilkS" user "Ref Des/Silkscreen Bottom")
		(1 "F.Mask" user "Board Geometry/Soldermask Top")
		(3 "B.Mask" user "Board Geometry/Soldermask Bottom")
		(17 "Dwgs.User" user "User.Drawings")
		(19 "Cmts.User" user "User.Comments")
		(21 "Eco1.User" user "User.Eco1")
		(23 "Eco2.User" user "User.Eco2")
		(25 "Edge.Cuts" user "Board Geometry/Outline")
		(27 "Margin" user)
		(31 "F.CrtYd" user "Package Geometry/Place Bound Top")
		(29 "B.CrtYd" user "Package Geometry/Place Bound Bottom")
		(35 "F.Fab" user "Ref Des/Assembly Top")
		(33 "B.Fab" user "Ref Des/Assembly Bottom")
	)
	(footprint ""
		(layer "F.Cu")
		(at 143.3322 -104.116378 -90)
		(property "Reference" "R346"
			(at 0 0 270)
			(layer "F.SilkS")
			(hide yes)
			(effects
				(font
					(size 1.27 1.27)
				)
			)
		)
		(property "Value" ""
			(at 0 0 270)
			(layer "F.Fab")
			(effects
				(font
					(size 1.27 1.27)
				)
			)
		)
		(duplicate_pad_numbers_are_jumpers no)
		(fp_line
			(start -0.7874 0.4064)
			(end -0.7874 -0.4064)
			(stroke
				(width 0.1524)
				(type default)
			)
			(layer "F.SilkS")
		)
		(fp_line
			(start 0.7874 0.4064)
			(end -0.7874 0.4064)
			(stroke
				(width 0.1524)
				(type default)
			)
			(layer "F.SilkS")
		)
		(fp_line
			(start -0.7874 -0.4064)
			(end 0.7874 -0.4064)
			(stroke
				(width 0.1524)
				(type default)
			)
			(layer "F.SilkS")
		)
		(fp_line
			(start 0.7874 -0.4064)
			(end 0.7874 0.4064)
			(stroke
				(width 0.1524)
				(type default)
			)
			(layer "F.SilkS")
		)
		(fp_line
			(start -0.67945 0.3048)
			(end -0.67945 -0.305054)
			(stroke
				(width 0.1)
				(type default)
			)
			(layer "F.Fab")
		)
		(fp_line
			(start -0.12065 0.3048)
			(end -0.67945 0.3048)
			(stroke
				(width 0.1)
				(type default)
			)
			(layer "F.Fab")
		)
		(fp_line
			(start 0.120396 0.3048)
			(end 0.120396 0.2794)
			(stroke
				(width 0.1)
				(type default)
			)
			(layer "F.Fab")
		)
		(fp_line
			(start 0.67945 0.3048)
			(end 0.120396 0.3048)
			(stroke
				(width 0.1)
				(type default)
			)
			(layer "F.Fab")
		)
		(fp_line
			(start -0.12065 0.2794)
			(end -0.12065 0.3048)
			(stroke
				(width 0.1)
				(type default)
			)
			(layer "F.Fab")
		)
		(fp_line
			(start 0.120396 0.2794)
			(end -0.12065 0.2794)
			(stroke
				(width 0.1)
				(type default)
			)
			(layer "F.Fab")
		)
		(fp_line
			(start -0.12065 -0.2794)
			(end 0.12065 -0.2794)
			(stroke
				(width 0.1)
				(type default)
			)
			(layer "F.Fab")
		)
		(fp_line
			(start 0.12065 -0.2794)
			(end 0.12065 -0.3048)
			(stroke
				(width 0.1)
				(type default)
			)
			(layer "F.Fab")
		)
		(fp_line
			(start 0.12065 -0.3048)
			(end 0.67945 -0.3048)
			(stroke
				(width 0.1)
				(type default)
			)
			(layer "F.Fab")
		)
		(fp_line
			(start 0.67945 -0.3048)
			(end 0.67945 0.3048)
			(stroke
				(width 0.1)
				(type default)
			)
			(layer "F.Fab")
		)
		(fp_line
			(start -0.67945 -0.305054)
			(end -0.12065 -0.305054)
			(stroke
				(width 0.1)
				(type default)
			)
			(layer "F.Fab")
		)
		(fp_line
			(start -0.12065 -0.305054)
			(end -0.12065 -0.2794)
			(stroke
				(width 0.1)
				(type default)
			)
			(layer "F.Fab")
		)
		(pad "1" smd circle
			(at -0.40005 0 270)
			(size 0 0)
			(layers "F.Cu" "F.Mask" "F.Paste")
			(net "H_CPU_ERR2_LVC1_R_N")
		)
		(pad "2" smd circle
			(at 0.40005 0 270)
			(size 0 0)
			(layers "F.Cu" "F.Mask" "F.Paste")
			(net "H_CPU_ERR2_LVC1_N")
		)
	)
	(footprint ""
		(layer "F.Cu")
		(at 80.981296 -70.78599)
		(property "Reference" "D65"
			(at -41.742106 50.178462 90)
			(unlocked yes)
			(layer "F.SilkS")
			(effects
				(font
					(size 0.635 0.4064)
					(thickness 0.1524)
				)
				(justify left)
			)
		)
		(property "Value" ""
			(at 0 0 0)
			(layer "F.Fab")
			(effects
				(font
					(size 1.27 1.27)
				)
			)
		)
		(duplicate_pad_numbers_are_jumpers no)
		(fp_line
			(start -0.90678 0.4826)
			(end -0.90678 -0.4699)
			(stroke
				(width 0.1524)
				(type default)
			)
			(layer "F.SilkS")
		)
		(fp_line
			(start -0.89408 -0.4826)
			(end 0.90678 -0.4826)
			(stroke
				(width 0.1524)
				(type default)
			)
			(layer "F.SilkS")
		)
		(fp_line
			(start -0.79248 -0.4826)
			(end 1.03378 -0.4826)
			(stroke
				(width 0.1524)
				(type default)
			)
			(layer "F.SilkS")
		)
		(fp_line
			(start -0.64008 -0.4826)
			(end 1.16078 -0.4826)
			(stroke
				(width 0.1524)
				(type default)
			)
			(layer "F.SilkS")
		)
		(fp_line
			(start 0.90678 -0.4826)
			(end 0.90678 0.4826)
			(stroke
				(width 0.1524)
				(type default)
			)
			(layer "F.SilkS")
		)
		(fp_line
			(start 0.90678 0.4826)
			(end -0.90678 0.4826)
			(stroke
				(width 0.1524)
				(type default)
			)
			(layer "F.SilkS")
		)
		(fp_line
			(start 1.03378 -0.4826)
			(end 1.03378 0.4826)
			(stroke
				(width 0.1524)
				(type default)
			)
			(layer "F.SilkS")
		)
		(fp_line
			(start 1.03378 0.4826)
			(end -0.79248 0.4826)
			(stroke
				(width 0.1524)
				(type default)
			)
			(layer "F.SilkS")
		)
		(fp_line
			(start 1.16078 -0.4826)
			(end 1.16078 0.4826)
			(stroke
				(width 0.1524)
				(type default)
			)
			(layer "F.SilkS")
		)
		(fp_line
			(start 1.16078 0.4826)
			(end -0.64008 0.4826)
			(stroke
				(width 0.1524)
				(type default)
			)
			(layer "F.SilkS")
		)
		(fp_line
			(start -0.499872 -0.249936)
			(end 0.499872 -0.249936)
			(stroke
				(width 0.1)
				(type default)
			)
			(layer "F.Fab")
		)
		(fp_line
			(start -0.499872 0.249936)
			(end -0.499872 -0.249936)
			(stroke
				(width 0.1)
				(type default)
			)
			(layer "F.Fab")
		)
		(fp_line
			(start 0.499872 -0.249936)
			(end 0.499872 0.249936)
			(stroke
				(width 0.1)
				(type default)
			)
			(layer "F.Fab")
		)
		(fp_line
			(start 0.499872 0.249936)
			(end -0.499872 0.249936)
			(stroke
				(width 0.1)
				(type default)
			)
			(layer "F.Fab")
		)
		(pad "A" smd rect
			(at -0.47498 0)
			(size 0.6096 0.7112)
			(layers "F.Cu" "F.Mask" "F.Paste")
			(net "LED_RST_PLD_CPU0_DRAM_AB_N")
		)
		(pad "C" smd rect
			(at 0.47498 0)
			(size 0.6096 0.7112)
			(layers "F.Cu" "F.Mask" "F.Paste")
			(net "LED_RST_PLD_CPU0_DRAM_AB_N_D")
		)
	)
)
